# S9S_MB_2U (Grand Teton) — schematic netlist excerpt (pin names and nets, part order shuffled) for the footprints in the layout excerpt that follows; sources: Cadence DE-HDL packaged netlist, KiCad conversion of 03242023_DA0F0TMBIJ0_F0T_Motherboard_J_brd_V01_OCP.brd

R3531  Q_RES  200K 1% EMPTY  pkg 0402LF  page 194 : A = SMB_PCIE_E1S_ISO_EN ; B = SMB_PCIE_E1S_ISO_EN_R
R580  Q_RES  33.2 1% CHIP  pkg 0402LF  page 241 : A = SMB_HOST_3V3AUX_SDA_R5 ; B = SMB_HOST_BMC_3V3AUX_SDA

(kicad_pcb
	(version 20260206)
	(generator "pcbnew")
	(generator_version "10.0")
	(general
		(thickness 1.6)
		(legacy_teardrops no)
	)
	(paper "A4")
	(title_block
		(title "03242023_DA0F0TMBIJ0_F0T_Motherboard_J_brd_V01_OCP.brd")
		(comment 1 "Grand Teton / footprints 3435-3436 of 6105")
	)
	(layers
		(0 "F.Cu" signal "TOP")
		(4 "In1.Cu" signal "GND")
		(6 "In2.Cu" signal "IN1")
		(8 "In3.Cu" signal "GND1")
		(10 "In4.Cu" signal "IN2")
		(12 "In5.Cu" signal "GND2")
		(14 "In6.Cu" signal "IN3")
		(16 "In7.Cu" signal "GND3")
		(18 "In8.Cu" signal "VCC")
		(20 "In9.Cu" signal "VCC1")
		(22 "In10.Cu" signal "GND4")
		(24 "In11.Cu" signal "IN4")
		(26 "In12.Cu" signal "GND5")
		(28 "In13.Cu" signal "IN5")
		(30 "In14.Cu" signal "GND6")
		(32 "In15.Cu" signal "IN6")
		(34 "In16.Cu" signal "GND7")
		(2 "B.Cu" signal "BOTTOM")
		(9 "F.Adhes" user "F.Adhesive")
		(11 "B.Adhes" user "B.Adhesive")
		(13 "F.Paste" user "Package Geometry/Pastemask Top")
		(15 "B.Paste" user "Package Geometry/Pastemask Bottom")
		(5 "F.SilkS" user "Ref Des/Silkscreen Top")
		(7 "B.SilkS" user "Ref Des/Silkscreen Bottom")
		(1 "F.Mask" user "Board Geometry/Soldermask Top")
		(3 "B.Mask" user "Board Geometry/Soldermask Bottom")
		(17 "Dwgs.User" user "User.Drawings")
		(19 "Cmts.User" user "User.Comments")
		(21 "Eco1.User" user "User.Eco1")
		(23 "Eco2.User" user "User.Eco2")
		(25 "Edge.Cuts" user "Board Geometry/Outline")
		(27 "Margin" user)
		(31 "F.CrtYd" user "Package Geometry/Place Bound Top")
		(29 "B.CrtYd" user "Package Geometry/Place Bound Bottom")
		(35 "F.Fab" user "Ref Des/Assembly Top")
		(33 "B.Fab" user "Ref Des/Assembly Bottom")
	)
	(footprint ""
		(layer "F.Cu")
		(at 4.699 -49.113948 180)
		(property "Reference" "R580"
			(at 0 0 180)
			(layer "F.SilkS")
			(hide yes)
			(effects
				(font
					(size 1.27 1.27)
				)
			)
		)
		(property "Value" ""
			(at 0 0 180)
			(layer "F.Fab")
			(effects
				(font
					(size 1.27 1.27)
				)
			)
		)
		(duplicate_pad_numbers_are_jumpers no)
		(fp_line
			(start 0.7874 0.4064)
			(end -0.7874 0.4064)
			(stroke
				(width 0.1524)
				(type default)
			)
			(layer "F.SilkS")
		)
		(fp_line
			(start 0.7874 -0.4064)
			(end 0.7874 0.4064)
			(stroke
				(width 0.1524)
				(type default)
			)
			(layer "F.SilkS")
		)
		(fp_line
			(start -0.7874 0.4064)
			(end -0.7874 -0.4064)
			(stroke
				(width 0.1524)
				(type default)
			)
			(layer "F.SilkS")
		)
		(fp_line
			(start -0.7874 -0.4064)
			(end 0.7874 -0.4064)
			(stroke
				(width 0.1524)
				(type default)
			)
			(layer "F.SilkS")
		)
		(fp_line
			(start 0.67945 0.3048)
			(end 0.120396 0.3048)
			(stroke
				(width 0.1)
				(type default)
			)
			(layer "F.Fab")
		)
		(fp_line
			(start 0.67945 -0.3048)
			(end 0.67945 0.3048)
			(stroke
				(width 0.1)
				(type default)
			)
			(layer "F.Fab")
		)
		(fp_line
			(start 0.12065 -0.2794)
			(end 0.12065 -0.3048)
			(stroke
				(width 0.1)
				(type default)
			)
			(layer "F.Fab")
		)
		(fp_line
			(start 0.12065 -0.3048)
			(end 0.67945 -0.3048)
			(stroke
				(width 0.1)
				(type default)
			)
			(layer "F.Fab")
		)
		(fp_line
			(start 0.120396 0.3048)
			(end 0.120396 0.2794)
			(stroke
				(width 0.1)
				(type default)
			)
			(layer "F.Fab")
		)
		(fp_line
			(start 0.120396 0.2794)
			(end -0.12065 0.2794)
			(stroke
				(width 0.1)
				(type default)
			)
			(layer "F.Fab")
		)
		(fp_line
			(start -0.12065 0.3048)
			(end -0.67945 0.3048)
			(stroke
				(width 0.1)
				(type default)
			)
			(layer "F.Fab")
		)
		(fp_line
			(start -0.12065 0.2794)
			(end -0.12065 0.3048)
			(stroke
				(width 0.1)
				(type default)
			)
			(layer "F.Fab")
		)
		(fp_line
			(start -0.12065 -0.2794)
			(end 0.12065 -0.2794)
			(stroke
				(width 0.1)
				(type default)
			)
			(layer "F.Fab")
		)
		(fp_line
			(start -0.12065 -0.305054)
			(end -0.12065 -0.2794)
			(stroke
				(width 0.1)
				(type default)
			)
			(layer "F.Fab")
		)
		(fp_line
			(start -0.67945 0.3048)
			(end -0.67945 -0.305054)
			(stroke
				(width 0.1)
				(type default)
			)
			(layer "F.Fab")
		)
		(fp_line
			(start -0.67945 -0.305054)
			(end -0.12065 -0.305054)
			(stroke
				(width 0.1)
				(type default)
			)
			(layer "F.Fab")
		)
		(pad "1" smd circle
			(at -0.40005 0 180)
			(size 0 0)
			(layers "F.Cu" "F.Mask" "F.Paste")
			(net "SMB_HOST_3V3AUX_SDA_R5")
		)
		(pad "2" smd circle
			(at 0.40005 0 180)
			(size 0 0)
			(layers "F.Cu" "F.Mask" "F.Paste")
			(net "SMB_HOST_BMC_3V3AUX_SDA")
		)
	)
	(footprint ""
		(layer "F.Cu")
		(at 210.74888 -44.795948)
		(property "Reference" "R3531"
			(at 0 0 0)
			(layer "F.SilkS")
			(hide yes)
			(effects
				(font
					(size 1.27 1.27)
				)
			)
		)
		(property "Value" ""
			(at 0 0 0)
			(layer "F.Fab")
			(effects
				(font
					(size 1.27 1.27)
				)
			)
		)
		(duplicate_pad_numbers_are_jumpers no)
		(fp_line
			(start -0.7874 -0.4064)
			(end 0.7874 -0.4064)
			(stroke
				(width 0.1524)
				(type default)
			)
			(layer "F.SilkS")
		)
		(fp_line
			(start -0.7874 0.4064)
			(end -0.7874 -0.4064)
			(stroke
				(width 0.1524)
				(type default)
			)
			(layer "F.SilkS")
		)
		(fp_line
			(start 0.7874 -0.4064)
			(end 0.7874 0.4064)
			(stroke
				(width 0.1524)
				(type default)
			)
			(layer "F.SilkS")
		)
		(fp_line
			(start 0.7874 0.4064)
			(end -0.7874 0.4064)
			(stroke
				(width 0.1524)
				(type default)
			)
			(layer "F.SilkS")
		)
		(fp_line
			(start -0.67945 -0.305054)
			(end -0.12065 -0.305054)
			(stroke
				(width 0.1)
				(type default)
			)
			(layer "F.Fab")
		)
		(fp_line
			(start -0.67945 0.3048)
			(end -0.67945 -0.305054)
			(stroke
				(width 0.1)
				(type default)
			)
			(layer "F.Fab")
		)
		(fp_line
			(start -0.12065 -0.305054)
			(end -0.12065 -0.2794)
			(stroke
				(width 0.1)
				(type default)
			)
			(layer "F.Fab")
		)
		(fp_line
			(start -0.12065 -0.2794)
			(end 0.12065 -0.2794)
			(stroke
				(width 0.1)
				(type default)
			)
			(layer "F.Fab")
		)
		(fp_line
			(start -0.12065 0.2794)
			(end -0.12065 0.3048)
			(stroke
				(width 0.1)
				(type default)
			)
			(layer "F.Fab")
		)
		(fp_line
			(start -0.12065 0.3048)
			(end -0.67945 0.3048)
			(stroke
				(width 0.1)
				(type default)
			)
			(layer "F.Fab")
		)
		(fp_line
			(start 0.120396 0.2794)
			(end -0.12065 0.2794)
			(stroke
				(width 0.1)
				(type default)
			)
			(layer "F.Fab")
		)
		(fp_line
			(start 0.120396 0.3048)
			(end 0.120396 0.2794)
			(stroke
				(width 0.1)
				(type default)
			)
			(layer "F.Fab")
		)
		(fp_line
			(start 0.12065 -0.3048)
			(end 0.67945 -0.3048)
			(stroke
				(width 0.1)
				(type default)
			)
			(layer "F.Fab")
		)
		(fp_line
			(start 0.12065 -0.2794)
			(end 0.12065 -0.3048)
			(stroke
				(width 0.1)
				(type default)
			)
			(layer "F.Fab")
		)
		(fp_line
			(start 0.67945 -0.3048)
			(end 0.67945 0.3048)
			(stroke
				(width 0.1)
				(type default)
			)
			(layer "F.Fab")
		)
		(fp_line
			(start 0.67945 0.3048)
			(end 0.120396 0.3048)
			(stroke
				(width 0.1)
				(type default)
			)
			(layer "F.Fab")
		)
		(pad "1" smd circle
			(at -0.40005 0)
			(size 0 0)
			(layers "F.Cu" "F.Mask" "F.Paste")
			(net "SMB_PCIE_E1S_ISO_EN")
		)
		(pad "2" smd circle
			(at 0.40005 0)
			(size 0 0)
			(layers "F.Cu" "F.Mask" "F.Paste")
			(net "SMB_PCIE_E1S_ISO_EN_R")
		)
	)
)
